(kicad_pcb
	(version 20241229)
	(generator "pcbnew")
	(generator_version "9.0")
	(general
		(thickness 1.6296)
		(legacy_teardrops no)
	)
	(paper "A3")
	(title_block
		(title "Thunderbolt to 10GbE adapter")
		(date "2026-04-21")
		(rev "1.1.0")
		(company "Antmicro Ltd")
		(comment 1 "www.antmicro.com")
		(comment 9 "footprints 72-76 of 703")
	)
	(layers
		(0 "F.Cu" signal)
		(4 "In1.Cu" signal)
		(6 "In2.Cu" signal)
		(8 "In3.Cu" signal)
		(10 "In4.Cu" signal)
		(12 "In5.Cu" signal)
		(14 "In6.Cu" signal)
		(2 "B.Cu" signal)
		(9 "F.Adhes" user "F.Adhesive")
		(11 "B.Adhes" user "B.Adhesive")
		(13 "F.Paste" user)
		(15 "B.Paste" user)
		(5 "F.SilkS" user "F.Silkscreen")
		(7 "B.SilkS" user "B.Silkscreen")
		(1 "F.Mask" user)
		(3 "B.Mask" user)
		(17 "Dwgs.User" user "User.Drawings")
		(19 "Cmts.User" user "User.Comments")
		(21 "Eco1.User" user "User.Eco1")
		(23 "Eco2.User" user "User.Eco2")
		(25 "Edge.Cuts" user)
		(27 "Margin" user)
		(31 "F.CrtYd" user "F.Courtyard")
		(29 "B.CrtYd" user "B.Courtyard")
		(35 "F.Fab" user)
		(33 "B.Fab" user)
	)
	(footprint "antmicro-footprints:Mech_Lightpipe_Mentor_1271.1001"
		(layer "F.Cu")
		(at 125 52.25)
		(descr "1x1  Horizontal Light Guide with transparent pipe")
		(tags "Horizontal, THT, MECHANICAL, MODULE")
		(property "Reference" "H5"
			(at -1.25 -2.45 0)
			(unlocked yes)
			(layer "F.SilkS")
			(effects
				(font
					(size 0.7 0.7)
					(thickness 0.15)
				)
				(justify left bottom)
			)
		)
		(property "Value" "Lightpipe_Mentor_1271.1001"
			(at 0 9 0)
			(unlocked yes)
			(layer "F.Fab")
			(effects
				(font
					(size 0.7 0.7)
					(thickness 0.15)
				)
				(justify left bottom)
			)
		)
		(property "Datasheet" "https://www.mentor.de.com/productpdfs/ll/ll14-20.pdf"
			(at 0 0 0)
			(layer "F.Fab")
			(hide yes)
			(effects
				(font
					(size 1.27 1.27)
					(thickness 0.15)
				)
			)
		)
		(property "Description" "Light Pipe, 14.45 mm, 1 Pipe, Circular, PC Board, Transparent"
			(at 0 0 0)
			(layer "F.Fab")
			(hide yes)
			(effects
				(font
					(size 1.27 1.27)
					(thickness 0.15)
				)
			)
		)
		(property "MPN" "1271.1001"
			(at 0 0 0)
			(unlocked yes)
			(layer "F.Fab")
			(hide yes)
			(effects
				(font
					(size 1 1)
					(thickness 0.15)
				)
			)
		)
		(property "Manufacturer" "Mentor Worldwide"
			(at 0 0 0)
			(unlocked yes)
			(layer "F.Fab")
			(hide yes)
			(effects
				(font
					(size 1 1)
					(thickness 0.15)
				)
			)
		)
		(property "Author" "Antmicro"
			(at 0 0 0)
			(unlocked yes)
			(layer "F.Fab")
			(hide yes)
			(effects
				(font
					(size 1 1)
					(thickness 0.15)
				)
			)
		)
		(property "License" "Apache-2.0"
			(at 0 0 0)
			(unlocked yes)
			(layer "F.Fab")
			(hide yes)
			(effects
				(font
					(size 1 1)
					(thickness 0.15)
				)
			)
		)
		(sheetname "/")
		(sheetfile "thunderbolt-to-10gbe-adapter.kicad_sch")
		(attr through_hole dnp)
		(fp_rect
			(start -1.55 -2.1)
			(end 1.55 1.3)
			(stroke
				(width 0.05)
				(type solid)
			)
			(fill no)
			(layer "F.SilkS")
		)
		(fp_rect
			(start -1.75 -2.3)
			(end 1.75 1.475)
			(stroke
				(width 0.05)
				(type solid)
			)
			(fill no)
			(layer "F.CrtYd")
		)
		(fp_rect
			(start -1.4732 -8.128)
			(end 1.4732 6.2484)
			(stroke
				(width 0.15)
				(type solid)
			)
			(fill no)
			(layer "F.Fab")
		)
		(fp_text user "License: Apache-2.0"
			(at -1.8 11.7 0)
			(layer "F.Fab")
			(effects
				(font
					(size 0.7 0.7)
					(thickness 0.15)
				)
				(justify left bottom)
			)
		)
		(fp_text user "${REFERENCE}"
			(at -1.8 12.9 0)
			(layer "F.Fab")
			(effects
				(font
					(size 0.7 0.7)
					(thickness 0.15)
				)
				(justify left bottom)
			)
		)
		(fp_text user "Author: Antmicro"
			(at -1.8 10.5 0)
			(layer "F.Fab")
			(effects
				(font
					(size 0.7 0.7)
					(thickness 0.15)
				)
				(justify left bottom)
			)
		)
		(pad "" np_thru_hole circle
			(at 0 0)
			(size 2.3 2.3)
			(drill 2.3)
			(layers "*.Cu" "*.Mask")
		)
	)
	(footprint "antmicro-footprints:R_0402_1005Metric"
		(layer "F.Cu")
		(at 125.02 91.579 180)
		(descr "Resistor SMD 0402")
		(tags "resistor SMD 0402")
		(property "Reference" "R115"
			(at 1.82 0.509 180)
			(layer "F.SilkS")
			(effects
				(font
					(size 0.7 0.7)
					(thickness 0.15)
				)
				(justify left bottom)
			)
		)
		(property "Value" "R_3k3_0402"
			(at -1.011843 1.772047 180)
			(layer "F.Fab")
			(effects
				(font
					(size 0.7 0.7)
					(thickness 0.15)
				)
				(justify left bottom)
			)
		)
		(property "Datasheet" "https://www.bourns.com/docs/product-datasheets/cr.pdf"
			(at 0 0 180)
			(layer "F.Fab")
			(hide yes)
			(effects
				(font
					(size 1.27 1.27)
					(thickness 0.15)
				)
			)
		)
		(property "Description" "SMD Chip Resistor, 3.3 kohm, ± 1%, 63 mW, 0402 [1005 Metric], Thick Film, General Purpose"
			(at 0 0 180)
			(layer "F.Fab")
			(hide yes)
			(effects
				(font
					(size 1.27 1.27)
					(thickness 0.15)
				)
			)
		)
		(property "MPN" "CR0402-FX-3301GLF"
			(at 0 0 180)
			(unlocked yes)
			(layer "F.Fab")
			(hide yes)
			(effects
				(font
					(size 1 1)
					(thickness 0.15)
				)
			)
		)
		(property "Manufacturer" "Bourns"
			(at 0 0 180)
			(unlocked yes)
			(layer "F.Fab")
			(hide yes)
			(effects
				(font
					(size 1 1)
					(thickness 0.15)
				)
			)
		)
		(property "License" "Apache-2.0"
			(at 0 0 180)
			(unlocked yes)
			(layer "F.Fab")
			(hide yes)
			(effects
				(font
					(size 1 1)
					(thickness 0.15)
				)
			)
		)
		(property "Author" "Antmicro"
			(at 0 0 180)
			(unlocked yes)
			(layer "F.Fab")
			(hide yes)
			(effects
				(font
					(size 1 1)
					(thickness 0.15)
				)
			)
		)
		(property "Val" "3k3"
			(at 0 0 180)
			(unlocked yes)
			(layer "F.Fab")
			(hide yes)
			(effects
				(font
					(size 1 1)
					(thickness 0.15)
				)
			)
		)
		(property "Tolerance" "1%"
			(at 0 0 180)
			(unlocked yes)
			(layer "F.Fab")
			(hide yes)
			(effects
				(font
					(size 1 1)
					(thickness 0.15)
				)
			)
		)
		(sheetname "/X710-AT2 PCIe/")
		(sheetfile "x710-at2-pcie.kicad_sch")
		(attr smd)
		(fp_rect
			(start -0.925 -0.47)
			(end 0.925 0.47)
			(stroke
				(width 0.05)
				(type default)
			)
			(fill no)
			(layer "F.CrtYd")
		)
		(fp_rect
			(start -0.5 -0.25)
			(end 0.5 0.25)
			(stroke
				(width 0.15)
				(type solid)
			)
			(fill no)
			(layer "F.Fab")
		)
		(fp_text user "License: Apache-2.0"
			(at -0.95 5.169 180)
			(layer "F.Fab")
			(effects
				(font
					(size 0.7 0.7)
					(thickness 0.15)
				)
				(justify left bottom)
			)
		)
		(fp_text user "Author: Antmicro"
			(at -0.95 4.169 180)
			(layer "F.Fab")
			(effects
				(font
					(size 0.7 0.7)
					(thickness 0.15)
				)
				(justify left bottom)
			)
		)
		(fp_text user "${REFERENCE}"
			(at -0.95 3.168 180)
			(layer "F.Fab")
			(effects
				(font
					(size 0.7 0.7)
					(thickness 0.15)
				)
				(justify left bottom)
			)
		)
		(pad "1" smd roundrect
			(at -0.48 0 180)
			(size 0.59 0.64)
			(layers "F.Cu" "F.Mask" "F.Paste")
			(roundrect_rratio 0.25)
			(net 8 "/X710-AT2 PCIe/PCIe_JTAG.JTDO")
			(pintype "passive")
		)
		(pad "2" smd roundrect
			(at 0.48 0 180)
			(size 0.59 0.64)
			(layers "F.Cu" "F.Mask" "F.Paste")
			(roundrect_rratio 0.25)
			(net 7 "+3V3")
			(pintype "passive")
		)
	)
	(footprint "antmicro-footprints:R_0402_1005Metric"
		(layer "F.Cu")
		(at 143.3 55.3)
		(descr "Resistor SMD 0402")
		(tags "resistor SMD 0402")
		(property "Reference" "R235"
			(at -3.7 0.4 0)
			(layer "F.SilkS")
			(effects
				(font
					(size 0.7 0.7)
					(thickness 0.15)
				)
				(justify left bottom)
			)
		)
		(property "Value" "R_1k_0402"
			(at -1.011843 1.772047 0)
			(layer "F.Fab")
			(effects
				(font
					(size 0.7 0.7)
					(thickness 0.15)
				)
				(justify left bottom)
			)
		)
		(property "Datasheet" "https://www.bourns.com/docs/product-datasheets/cr.pdf"
			(at 0 0 0)
			(layer "F.Fab")
			(hide yes)
			(effects
				(font
					(size 1.27 1.27)
					(thickness 0.15)
				)
			)
		)
		(property "Description" "SMD Chip Resistor, 1 kohm, ± 1%, 63 mW, 0402 [1005 Metric], Thick Film, General Purpose"
			(at 0 0 0)
			(layer "F.Fab")
			(hide yes)
			(effects
				(font
					(size 1.27 1.27)
					(thickness 0.15)
				)
			)
		)
		(property "MPN" "CR0402-FX-1001GLF"
			(at 0 0 0)
			(unlocked yes)
			(layer "F.Fab")
			(hide yes)
			(effects
				(font
					(size 1 1)
					(thickness 0.15)
				)
			)
		)
		(property "Manufacturer" "Bourns"
			(at 0 0 0)
			(unlocked yes)
			(layer "F.Fab")
			(hide yes)
			(effects
				(font
					(size 1 1)
					(thickness 0.15)
				)
			)
		)
		(property "License" "Apache-2.0"
			(at 0 0 0)
			(unlocked yes)
			(layer "F.Fab")
			(hide yes)
			(effects
				(font
					(size 1 1)
					(thickness 0.15)
				)
			)
		)
		(property "Author" "Antmicro"
			(at 0 0 0)
			(unlocked yes)
			(layer "F.Fab")
			(hide yes)
			(effects
				(font
					(size 1 1)
					(thickness 0.15)
				)
			)
		)
		(property "Val" "1k"
			(at 0 0 0)
			(unlocked yes)
			(layer "F.Fab")
			(hide yes)
			(effects
				(font
					(size 1 1)
					(thickness 0.15)
				)
			)
		)
		(property "Tolerance" "1%"
			(at 0 0 0)
			(unlocked yes)
			(layer "F.Fab")
			(hide yes)
			(effects
				(font
					(size 1 1)
					(thickness 0.15)
				)
			)
		)
		(sheetname "/Power input/")
		(sheetfile "power_input.kicad_sch")
		(attr smd)
		(fp_rect
			(start -0.925 -0.47)
			(end 0.925 0.47)
			(stroke
				(width 0.05)
				(type default)
			)
			(fill no)
			(layer "F.CrtYd")
		)
		(fp_rect
			(start -0.5 -0.25)
			(end 0.5 0.25)
			(stroke
				(width 0.15)
				(type solid)
			)
			(fill no)
			(layer "F.Fab")
		)
		(fp_text user "Author: Antmicro"
			(at -0.95 4.169 0)
			(layer "F.Fab")
			(effects
				(font
					(size 0.7 0.7)
					(thickness 0.15)
				)
				(justify left bottom)
			)
		)
		(fp_text user "${REFERENCE}"
			(at -0.95 3.168 0)
			(layer "F.Fab")
			(effects
				(font
					(size 0.7 0.7)
					(thickness 0.15)
				)
				(justify left bottom)
			)
		)
		(fp_text user "License: Apache-2.0"
			(at -0.95 5.169 0)
			(layer "F.Fab")
			(effects
				(font
					(size 0.7 0.7)
					(thickness 0.15)
				)
				(justify left bottom)
			)
		)
		(pad "1" smd roundrect
			(at -0.48 0)
			(size 0.59 0.64)
			(layers "F.Cu" "F.Mask" "F.Paste")
			(roundrect_rratio 0.25)
			(net 23 "GND")
			(pintype "passive")
		)
		(pad "2" smd roundrect
			(at 0.48 0)
			(size 0.59 0.64)
			(layers "F.Cu" "F.Mask" "F.Paste")
			(roundrect_rratio 0.25)
			(net 13 "/Power input/5V_JACK")
			(pintype "passive")
		)
	)
	(footprint "antmicro-footprints:C_0402_1005Metric"
		(layer "F.Cu")
		(at 116.6 132.4)
		(descr "Capacitor SMD 0402")
		(tags "capacitor SMD 0402")
		(property "Reference" "C42"
			(at -1.4 1.4 0)
			(layer "F.SilkS")
			(effects
				(font
					(size 0.7 0.7)
					(thickness 0.15)
				)
				(justify left bottom)
			)
		)
		(property "Value" "C_10p_0402"
			(at -1.022927 2.155213 0)
			(layer "F.Fab")
			(effects
				(font
					(size 0.7 0.7)
					(thickness 0.15)
				)
				(justify left bottom)
			)
		)
		(property "Datasheet" "https://www.murata.com/products/productdetail?partno=GCM1555C1H100GA16%23"
			(at 0 0 0)
			(layer "F.Fab")
			(hide yes)
			(effects
				(font
					(size 1.27 1.27)
					(thickness 0.15)
				)
			)
		)
		(property "Description" "SMD Multilayer Ceramic Capacitor, 10 pF, 50 V, 0402 [1005 Metric], ± 2%, C0G / NP0, GCM"
			(at 0 0 0)
			(layer "F.Fab")
			(hide yes)
			(effects
				(font
					(size 1.27 1.27)
					(thickness 0.15)
				)
			)
		)
		(property "MPN" "GCM1555C1H100GA16D"
			(at 0 0 0)
			(unlocked yes)
			(layer "F.Fab")
			(hide yes)
			(effects
				(font
					(size 1 1)
					(thickness 0.15)
				)
			)
		)
		(property "Manufacturer" "Murata"
			(at 0 0 0)
			(unlocked yes)
			(layer "F.Fab")
			(hide yes)
			(effects
				(font
					(size 1 1)
					(thickness 0.15)
				)
			)
		)
		(property "License" "Apache-2.0"
			(at 0 0 0)
			(unlocked yes)
			(layer "F.Fab")
			(hide yes)
			(effects
				(font
					(size 1 1)
					(thickness 0.15)
				)
			)
		)
		(property "Val" "10p"
			(at 0 0 0)
			(unlocked yes)
			(layer "F.Fab")
			(hide yes)
			(effects
				(font
					(size 1 1)
					(thickness 0.15)
				)
			)
		)
		(property "Voltage" "50V"
			(at 0 0 0)
			(unlocked yes)
			(layer "F.Fab")
			(hide yes)
			(effects
				(font
					(size 1 1)
					(thickness 0.15)
				)
			)
		)
		(property "Dielectric" "C0G"
			(at 0 0 0)
			(unlocked yes)
			(layer "F.Fab")
			(hide yes)
			(effects
				(font
					(size 1 1)
					(thickness 0.15)
				)
			)
		)
		(property "Author" "Antmicro"
			(at 0 0 0)
			(unlocked yes)
			(layer "F.Fab")
			(hide yes)
			(effects
				(font
					(size 1 1)
					(thickness 0.15)
				)
			)
		)
		(sheetname "/TB Controller/")
		(sheetfile "tb.kicad_sch")
		(attr smd)
		(fp_rect
			(start -0.925 -0.47)
			(end 0.925 0.47)
			(stroke
				(width 0.05)
				(type default)
			)
			(fill no)
			(layer "F.CrtYd")
		)
		(fp_line
			(start -0.494 -0.25)
			(end 0.504 -0.25)
			(stroke
				(width 0.15)
				(type solid)
			)
			(layer "F.Fab")
		)
		(fp_line
			(start -0.494 0.248)
			(end -0.494 -0.25)
			(stroke
				(width 0.15)
				(type solid)
			)
			(layer "F.Fab")
		)
		(fp_line
			(start 0.504 -0.25)
			(end 0.504 0.248)
			(stroke
				(width 0.15)
				(type solid)
			)
			(layer "F.Fab")
		)
		(fp_line
			(start 0.504 0.248)
			(end -0.494 0.248)
			(stroke
				(width 0.15)
				(type solid)
			)
			(layer "F.Fab")
		)
		(fp_text user "License: Apache-2.0"
			(at -0.939 5.799 0)
			(layer "F.Fab")
			(effects
				(font
					(size 0.7 0.7)
					(thickness 0.15)
				)
				(justify left bottom)
			)
		)
		(fp_text user "${REFERENCE}"
			(at -0.939 4.599 0)
			(layer "F.Fab")
			(effects
				(font
					(size 0.7 0.7)
					(thickness 0.15)
				)
				(justify left bottom)
			)
		)
		(fp_text user "Author: Antmicro"
			(at -0.939 3.399 0)
			(layer "F.Fab")
			(effects
				(font
					(size 0.7 0.7)
					(thickness 0.15)
				)
				(justify left bottom)
			)
		)
		(pad "1" smd roundrect
			(at -0.48 0)
			(size 0.59 0.64)
			(layers "F.Cu" "F.Mask" "F.Paste")
			(roundrect_rratio 0.25)
			(net 330 "/TB Controller/XTAL_25_IN")
			(pintype "passive")
		)
		(pad "2" smd roundrect
			(at 0.48 0)
			(size 0.59 0.64)
			(layers "F.Cu" "F.Mask" "F.Paste")
			(roundrect_rratio 0.25)
			(net 23 "GND")
			(pintype "passive")
		)
	)
	(footprint "antmicro-footprints:R_0402_1005Metric"
		(layer "F.Cu")
		(at 153.8 45.9)
		(descr "Resistor SMD 0402")
		(tags "resistor SMD 0402")
		(property "Reference" "R227"
			(at -3.8 0.2 0)
			(layer "F.SilkS")
			(effects
				(font
					(size 0.7 0.7)
					(thickness 0.15)
				)
				(justify left bottom)
			)
		)
		(property "Value" "R_3k24_0402"
			(at -1.011843 1.772047 0)
			(layer "F.Fab")
			(effects
				(font
					(size 0.7 0.7)
					(thickness 0.15)
				)
				(justify left bottom)
			)
		)
		(property "Datasheet" "https://www.farnell.com/datasheets/3795017.pdf"
			(at 0 0 0)
			(layer "F.Fab")
			(hide yes)
			(effects
				(font
					(size 1.27 1.27)
					(thickness 0.15)
				)
			)
		)
		(property "Description" "SMD Chip Resistor, 3.24 kohm, ± 1%, 62.5 mW, 0402 [1005 Metric], Thick Film, General Purpose"
			(at 0 0 0)
			(layer "F.Fab")
			(hide yes)
			(effects
				(font
					(size 1.27 1.27)
					(thickness 0.15)
				)
			)
		)
		(property "MPN" "RMCF0402FT3K24"
			(at 0 0 0)
			(unlocked yes)
			(layer "F.Fab")
			(hide yes)
			(effects
				(font
					(size 1 1)
					(thickness 0.15)
				)
			)
		)
		(property "Manufacturer" "Stackpole Electronics"
			(at 0 0 0)
			(unlocked yes)
			(layer "F.Fab")
			(hide yes)
			(effects
				(font
					(size 1 1)
					(thickness 0.15)
				)
			)
		)
		(property "License" "Apache-2.0"
			(at 0 0 0)
			(unlocked yes)
			(layer "F.Fab")
			(hide yes)
			(effects
				(font
					(size 1 1)
					(thickness 0.15)
				)
			)
		)
		(property "Author" "Antmicro"
			(at 0 0 0)
			(unlocked yes)
			(layer "F.Fab")
			(hide yes)
			(effects
				(font
					(size 1 1)
					(thickness 0.15)
				)
			)
		)
		(property "Val" "3k24"
			(at 0 0 0)
			(unlocked yes)
			(layer "F.Fab")
			(hide yes)
			(effects
				(font
					(size 1 1)
					(thickness 0.15)
				)
			)
		)
		(property "Tolerance" "1%"
			(at 0 0 0)
			(unlocked yes)
			(layer "F.Fab")
			(hide yes)
			(effects
				(font
					(size 1 1)
					(thickness 0.15)
				)
			)
		)
		(sheetname "/Power input/")
		(sheetfile "power_input.kicad_sch")
		(attr smd)
		(fp_rect
			(start -0.925 -0.47)
			(end 0.925 0.47)
			(stroke
				(width 0.05)
				(type default)
			)
			(fill no)
			(layer "F.CrtYd")
		)
		(fp_rect
			(start -0.5 -0.25)
			(end 0.5 0.25)
			(stroke
				(width 0.15)
				(type solid)
			)
			(fill no)
			(layer "F.Fab")
		)
		(fp_text user "Author: Antmicro"
			(at -0.95 4.169 0)
			(layer "F.Fab")
			(effects
				(font
					(size 0.7 0.7)
					(thickness 0.15)
				)
				(justify left bottom)
			)
		)
		(fp_text user "License: Apache-2.0"
			(at -0.95 5.169 0)
			(layer "F.Fab")
			(effects
				(font
					(size 0.7 0.7)
					(thickness 0.15)
				)
				(justify left bottom)
			)
		)
		(fp_text user "${REFERENCE}"
			(at -0.95 3.168 0)
			(layer "F.Fab")
			(effects
				(font
					(size 0.7 0.7)
					(thickness 0.15)
				)
				(justify left bottom)
			)
		)
		(pad "1" smd roundrect
			(at -0.48 0)
			(size 0.59 0.64)
			(layers "F.Cu" "F.Mask" "F.Paste")
			(roundrect_rratio 0.25)
			(net 23 "GND")
			(pintype "passive")
		)
		(pad "2" smd roundrect
			(at 0.48 0)
			(size 0.59 0.64)
			(layers "F.Cu" "F.Mask" "F.Paste")
			(roundrect_rratio 0.25)
			(net 344 "/Power input/5V_EN")
			(pintype "passive")
		)
	)
)
